# BASEBOARD_FAB2 (Tioga Pass) — schematic netlist excerpt (pin names and nets, part order shuffled) for the footprints in the layout excerpt that follows; sources: Cadence DE-HDL packaged netlist, KiCad conversion of Wiwynn_Tioga_Pass_MB.brd

R3N4  RES  20.0K 1% CHIP  pkg 0402  page 137 : A = P3V3_RTC_STBY ; B = RST_SRTCRST_N
R9M6  RES  49.9 1% EMPTY  pkg 0402  page 226 : A = PVCCIO_CPU1 ; B = SVID_CLK1_CPU1_R

U1M1  TTL1G08  NC7SZ08 IC  pkg SOTLF  page 177
  A(0)  = LED_SATA_ACT_R_N
  B(0)  = LED_SAS_ACT_R_N
  Y(0)  = FP_LED_HDD_ACTIVITY_AND_N

(kicad_pcb
	(version 20260206)
	(generator "pcbnew")
	(generator_version "10.0")
	(general
		(thickness 1.6)
		(legacy_teardrops no)
	)
	(paper "A4")
	(title_block
		(title "Wiwynn_Tioga_Pass_MB.brd")
		(comment 1 "Tioga Pass / footprints 2736-2738 of 4770")
	)
	(layers
		(0 "F.Cu" signal "TOP")
		(4 "In1.Cu" signal "L2GND")
		(6 "In2.Cu" signal "L3")
		(8 "In3.Cu" signal "L4GND")
		(10 "In4.Cu" signal "L5")
		(12 "In5.Cu" signal "L6GND")
		(14 "In6.Cu" signal "L7VCC")
		(16 "In7.Cu" signal "L8VCC")
		(18 "In8.Cu" signal "L9GND")
		(20 "In9.Cu" signal "L10")
		(22 "In10.Cu" signal "L11GND")
		(24 "In11.Cu" signal "L12")
		(26 "In12.Cu" signal "L13GND")
		(2 "B.Cu" signal "BOTTOM")
		(9 "F.Adhes" user "F.Adhesive")
		(11 "B.Adhes" user "B.Adhesive")
		(13 "F.Paste" user "Package Geometry/Pastemask Top")
		(15 "B.Paste" user "Package Geometry/Pastemask Bottom")
		(5 "F.SilkS" user "Ref Des/Silkscreen Top")
		(7 "B.SilkS" user "Ref Des/Silkscreen Bottom")
		(1 "F.Mask" user "Board Geometry/Soldermask Top")
		(3 "B.Mask" user "Board Geometry/Soldermask Bottom")
		(17 "Dwgs.User" user "User.Drawings")
		(19 "Cmts.User" user "User.Comments")
		(21 "Eco1.User" user "User.Eco1")
		(23 "Eco2.User" user "User.Eco2")
		(25 "Edge.Cuts" user "Board Geometry/Outline")
		(27 "Margin" user)
		(31 "F.CrtYd" user "Package Geometry/Place Bound Top")
		(29 "B.CrtYd" user "Package Geometry/Place Bound Bottom")
		(35 "F.Fab" user "Ref Des/Assembly Top")
		(33 "B.Fab" user "Ref Des/Assembly Bottom")
	)
	(footprint ""
		(layer "B.Cu")
		(at 374.777 -100.3046 90)
		(property "Reference" "R3N4"
			(at 0 0 90)
			(layer "B.SilkS")
			(hide yes)
			(effects
				(font
					(size 1.27 1.27)
				)
				(justify mirror)
			)
		)
		(property "Value" ""
			(at 0 0 90)
			(layer "B.Fab")
			(effects
				(font
					(size 1.27 1.27)
				)
				(justify mirror)
			)
		)
		(duplicate_pad_numbers_are_jumpers no)
		(fp_poly
			(pts
				(xy 0.2794 -0.1016) (xy -0.2794 -0.1016) (xy -0.2794 0.9906) (xy 0.2794 0.9906)
			)
			(stroke
				(width 0)
				(type default)
			)
			(fill no)
			(layer "B.CrtYd")
		)
		(fp_line
			(start 0.2794 -0.1016)
			(end 0.2794 0.9906)
			(stroke
				(width 0.1)
				(type default)
			)
			(layer "B.Fab")
		)
		(fp_line
			(start -0.2794 -0.1016)
			(end 0.2794 -0.1016)
			(stroke
				(width 0.1)
				(type default)
			)
			(layer "B.Fab")
		)
		(fp_line
			(start 0.2794 0.9906)
			(end -0.2794 0.9906)
			(stroke
				(width 0.1)
				(type default)
			)
			(layer "B.Fab")
		)
		(fp_line
			(start -0.2794 0.9906)
			(end -0.2794 -0.1016)
			(stroke
				(width 0.1)
				(type default)
			)
			(layer "B.Fab")
		)
		(pad "1" smd rect
			(at 0 0 270)
			(size 0.508 0.508)
			(layers "B.Cu" "B.Mask" "B.Paste")
			(net "P3V3_RTC_STBY")
		)
		(pad "2" smd rect
			(at 0 0.889 270)
			(size 0.508 0.508)
			(layers "B.Cu" "B.Mask" "B.Paste")
			(net "RST_SRTCRST_N")
		)
		(zone
			(layer "B.Cu")
			(hatch none 0.5)
			(connect_pads
				(clearance 0)
			)
			(min_thickness 0.25)
			(keepout
				(tracks allowed)
				(vias not_allowed)
				(pads allowed)
				(copperpour not_allowed)
				(footprints allowed)
			)
			(placement
				(enabled no)
				(sheetname "")
			)
			(fill
				(thermal_gap 0.5)
				(thermal_bridge_width 0.5)
				(island_removal_mode 0)
			)
			(polygon
				(pts
					(xy 375.031 -100.5586) (xy 375.031 -100.0506) (xy 375.412 -100.0506) (xy 375.412 -100.5586)
				)
			)
		)
		(zone
			(layer "B.Cu")
			(hatch none 0.5)
			(connect_pads
				(clearance 0)
			)
			(min_thickness 0.25)
			(keepout
				(tracks not_allowed)
				(vias allowed)
				(pads allowed)
				(copperpour not_allowed)
				(footprints allowed)
			)
			(placement
				(enabled no)
				(sheetname "")
			)
			(fill
				(thermal_gap 0.5)
				(thermal_bridge_width 0.5)
				(island_removal_mode 0)
			)
			(polygon
				(pts
					(xy 375.412 -100.5586) (xy 375.412 -100.0506) (xy 375.031 -100.0506) (xy 375.031 -100.5586)
				)
			)
		)
	)
	(footprint ""
		(layer "B.Cu")
		(at -2.5146 -128.6002 -90)
		(property "Reference" "R9M6"
			(at 0 0 90)
			(layer "B.SilkS")
			(hide yes)
			(effects
				(font
					(size 1.27 1.27)
				)
				(justify mirror)
			)
		)
		(property "Value" ""
			(at 0 0 90)
			(layer "B.Fab")
			(effects
				(font
					(size 1.27 1.27)
				)
				(justify mirror)
			)
		)
		(duplicate_pad_numbers_are_jumpers no)
		(fp_rect
			(start 0.2794 0.9906)
			(end -0.2794 -0.1016)
			(stroke
				(width 0)
				(type default)
			)
			(fill no)
			(layer "B.CrtYd")
		)
		(fp_line
			(start -0.2794 0.9906)
			(end -0.2794 -0.1016)
			(stroke
				(width 0.1)
				(type default)
			)
			(layer "B.Fab")
		)
		(fp_line
			(start 0.2794 0.9906)
			(end -0.2794 0.9906)
			(stroke
				(width 0.1)
				(type default)
			)
			(layer "B.Fab")
		)
		(fp_line
			(start -0.2794 -0.1016)
			(end 0.2794 -0.1016)
			(stroke
				(width 0.1)
				(type default)
			)
			(layer "B.Fab")
		)
		(fp_line
			(start 0.2794 -0.1016)
			(end 0.2794 0.9906)
			(stroke
				(width 0.1)
				(type default)
			)
			(layer "B.Fab")
		)
		(pad "1" smd rect
			(at 0 0 90)
			(size 0.508 0.508)
			(layers "B.Cu" "B.Mask" "B.Paste")
			(net "PVCCIO_CPU1")
		)
		(pad "2" smd rect
			(at 0 0.889 90)
			(size 0.508 0.508)
			(layers "B.Cu" "B.Mask" "B.Paste")
			(net "SVID_CLK1_CPU1_R")
		)
		(zone
			(layer "B.Cu")
			(hatch none 0.5)
			(connect_pads
				(clearance 0)
			)
			(min_thickness 0.25)
			(keepout
				(tracks not_allowed)
				(vias allowed)
				(pads allowed)
				(copperpour not_allowed)
				(footprints allowed)
			)
			(placement
				(enabled no)
				(sheetname "")
			)
			(fill
				(thermal_gap 0.5)
				(thermal_bridge_width 0.5)
				(island_removal_mode 0)
			)
			(polygon
				(pts
					(xy -3.1496 -128.3462) (xy -2.7686 -128.3462) (xy -2.7686 -128.8542) (xy -3.1496 -128.8542)
				)
			)
		)
		(zone
			(layer "B.Cu")
			(hatch none 0.5)
			(connect_pads
				(clearance 0)
			)
			(min_thickness 0.25)
			(keepout
				(tracks allowed)
				(vias not_allowed)
				(pads allowed)
				(copperpour not_allowed)
				(footprints allowed)
			)
			(placement
				(enabled no)
				(sheetname "")
			)
			(fill
				(thermal_gap 0.5)
				(thermal_bridge_width 0.5)
				(island_removal_mode 0)
			)
			(polygon
				(pts
					(xy -3.1496 -128.3462) (xy -2.7686 -128.3462) (xy -2.7686 -128.8542) (xy -3.1496 -128.8542)
				)
			)
		)
	)
	(footprint ""
		(layer "B.Cu")
		(at 494.75136 -126.5174 -90)
		(property "Reference" "U1M1"
			(at 0 0 90)
			(layer "B.SilkS")
			(hide yes)
			(effects
				(font
					(size 1.27 1.27)
				)
				(justify mirror)
			)
		)
		(property "Value" ""
			(at 0 0 90)
			(layer "B.Fab")
			(effects
				(font
					(size 1.27 1.27)
				)
				(justify mirror)
			)
		)
		(duplicate_pad_numbers_are_jumpers no)
		(fp_circle
			(center 0.813308 -0.4826)
			(end 0.813308 -0.6096)
			(stroke
				(width 0.254)
				(type default)
			)
			(fill no)
			(layer "B.SilkS")
		)
		(fp_poly
			(pts
				(xy -0.21463 -0.450088) (xy -1.56337 -0.450088) (xy -1.56337 1.75006) (xy -0.21463 1.75006)
			)
			(stroke
				(width 0)
				(type default)
			)
			(fill no)
			(layer "B.CrtYd")
		)
		(fp_line
			(start -1.56337 1.75006)
			(end -0.21463 1.75006)
			(stroke
				(width 0.1)
				(type default)
			)
			(layer "B.Fab")
		)
		(fp_line
			(start -0.21463 1.75006)
			(end -0.21463 -0.450088)
			(stroke
				(width 0.1)
				(type default)
			)
			(layer "B.Fab")
		)
		(fp_line
			(start -1.56337 -0.450088)
			(end -1.56337 1.75006)
			(stroke
				(width 0.1)
				(type default)
			)
			(layer "B.Fab")
		)
		(fp_line
			(start -0.21463 -0.450088)
			(end -1.56337 -0.450088)
			(stroke
				(width 0.1)
				(type default)
			)
			(layer "B.Fab")
		)
		(fp_circle
			(center -0.544322 -0.583946)
			(end -0.544322 -0.710946)
			(stroke
				(width 0.254)
				(type default)
			)
			(fill no)
			(layer "B.Fab")
		)
		(pad "1" smd rect
			(at 0 0 90)
			(size 1.016 0.381)
			(layers "B.Cu" "B.Mask" "B.Paste")
			(net "LED_SATA_ACT_R_N")
		)
		(pad "2" smd rect
			(at 0 0.649986 90)
			(size 1.016 0.381)
			(layers "B.Cu" "B.Mask" "B.Paste")
			(net "LED_SAS_ACT_R_N")
		)
		(pad "3" smd rect
			(at 0 1.299972 90)
			(size 1.016 0.381)
			(layers "B.Cu" "B.Mask" "B.Paste")
			(net "GND")
		)
		(pad "4" smd rect
			(at -1.778 1.299972 90)
			(size 1.016 0.381)
			(layers "B.Cu" "B.Mask" "B.Paste")
			(net "FP_LED_HDD_ACTIVITY_AND_N")
		)
		(pad "5" smd rect
			(at -1.778 0 90)
			(size 1.016 0.381)
			(layers "B.Cu" "B.Mask" "B.Paste")
			(net "P3V3")
		)
	)
)
